# BASEBOARD_FAB2 (Tioga Pass) — schematic netlist excerpt (pin names and nets, part order shuffled) for the footprints in the layout excerpt that follows; sources: Cadence DE-HDL packaged netlist, KiCad conversion of Wiwynn_Tioga_Pass_MB.brd

C1A11  SC1U10V2KX-4-GP  10%  pkg SMD-BCG6  page 227 : \1\ = P5V_STBY ; \2\ = GND
C1R20  CAP_A  0.1UF 16V 10% X7R  pkg 0402V  page 139 : A = P3V3_STBY ; B = GND
C5L8  CAP_A  47UF 4V 20% X5R  pkg 0603V  page 220 : A = PVDDQ_DEF ; B = GND

(kicad_pcb
	(version 20260206)
	(generator "pcbnew")
	(generator_version "10.0")
	(general
		(thickness 1.6)
		(legacy_teardrops no)
	)
	(paper "A4")
	(title_block
		(title "Wiwynn_Tioga_Pass_MB.brd")
		(comment 1 "Tioga Pass / footprints 3513-3515 of 4770")
	)
	(layers
		(0 "F.Cu" signal "TOP")
		(4 "In1.Cu" signal "L2GND")
		(6 "In2.Cu" signal "L3")
		(8 "In3.Cu" signal "L4GND")
		(10 "In4.Cu" signal "L5")
		(12 "In5.Cu" signal "L6GND")
		(14 "In6.Cu" signal "L7VCC")
		(16 "In7.Cu" signal "L8VCC")
		(18 "In8.Cu" signal "L9GND")
		(20 "In9.Cu" signal "L10")
		(22 "In10.Cu" signal "L11GND")
		(24 "In11.Cu" signal "L12")
		(26 "In12.Cu" signal "L13GND")
		(2 "B.Cu" signal "BOTTOM")
		(9 "F.Adhes" user "F.Adhesive")
		(11 "B.Adhes" user "B.Adhesive")
		(13 "F.Paste" user "Package Geometry/Pastemask Top")
		(15 "B.Paste" user "Package Geometry/Pastemask Bottom")
		(5 "F.SilkS" user "Ref Des/Silkscreen Top")
		(7 "B.SilkS" user "Ref Des/Silkscreen Bottom")
		(1 "F.Mask" user "Board Geometry/Soldermask Top")
		(3 "B.Mask" user "Board Geometry/Soldermask Bottom")
		(17 "Dwgs.User" user "User.Drawings")
		(19 "Cmts.User" user "User.Comments")
		(21 "Eco1.User" user "User.Eco1")
		(23 "Eco2.User" user "User.Eco2")
		(25 "Edge.Cuts" user "Board Geometry/Outline")
		(27 "Margin" user)
		(31 "F.CrtYd" user "Package Geometry/Place Bound Top")
		(29 "B.CrtYd" user "Package Geometry/Place Bound Bottom")
		(35 "F.Fab" user "Ref Des/Assembly Top")
		(33 "B.Fab" user "Ref Des/Assembly Bottom")
	)
	(footprint ""
		(layer "B.Cu")
		(at 488.2515 -43.5864 -90)
		(property "Reference" "C1R20"
			(at 0 0 90)
			(layer "B.SilkS")
			(hide yes)
			(effects
				(font
					(size 1.27 1.27)
				)
				(justify mirror)
			)
		)
		(property "Value" ""
			(at 0 0 90)
			(layer "B.Fab")
			(effects
				(font
					(size 1.27 1.27)
				)
				(justify mirror)
			)
		)
		(duplicate_pad_numbers_are_jumpers no)
		(fp_poly
			(pts
				(xy -0.3048 -0.1016) (xy -0.3048 0.9906) (xy 0.3048 0.9906) (xy 0.3048 -0.1016)
			)
			(stroke
				(width 0)
				(type default)
			)
			(fill no)
			(layer "B.CrtYd")
		)
		(fp_line
			(start -0.3048 0.9906)
			(end -0.3048 -0.1016)
			(stroke
				(width 0.1)
				(type default)
			)
			(layer "B.Fab")
		)
		(fp_line
			(start 0.3048 0.9906)
			(end -0.3048 0.9906)
			(stroke
				(width 0.1)
				(type default)
			)
			(layer "B.Fab")
		)
		(fp_line
			(start -0.3048 -0.1016)
			(end 0.3048 -0.1016)
			(stroke
				(width 0.1)
				(type default)
			)
			(layer "B.Fab")
		)
		(fp_line
			(start 0.3048 -0.1016)
			(end 0.3048 0.9906)
			(stroke
				(width 0.1)
				(type default)
			)
			(layer "B.Fab")
		)
		(pad "1" smd rect
			(at 0 0 90)
			(size 0.508 0.508)
			(layers "B.Cu" "B.Mask" "B.Paste")
			(net "P3V3_STBY")
		)
		(pad "2" smd rect
			(at 0 0.889 90)
			(size 0.508 0.508)
			(layers "B.Cu" "B.Mask" "B.Paste")
			(net "GND")
		)
		(zone
			(layer "B.Cu")
			(hatch none 0.5)
			(connect_pads
				(clearance 0)
			)
			(min_thickness 0.25)
			(keepout
				(tracks not_allowed)
				(vias allowed)
				(pads allowed)
				(copperpour not_allowed)
				(footprints allowed)
			)
			(placement
				(enabled no)
				(sheetname "")
			)
			(fill
				(thermal_gap 0.5)
				(thermal_bridge_width 0.5)
				(island_removal_mode 0)
			)
			(polygon
				(pts
					(xy 487.6165 -43.3324) (xy 487.6165 -43.8404) (xy 487.9975 -43.8404) (xy 487.9975 -43.3324)
				)
			)
		)
		(zone
			(layer "B.Cu")
			(hatch none 0.5)
			(connect_pads
				(clearance 0)
			)
			(min_thickness 0.25)
			(keepout
				(tracks allowed)
				(vias not_allowed)
				(pads allowed)
				(copperpour not_allowed)
				(footprints allowed)
			)
			(placement
				(enabled no)
				(sheetname "")
			)
			(fill
				(thermal_gap 0.5)
				(thermal_bridge_width 0.5)
				(island_removal_mode 0)
			)
			(polygon
				(pts
					(xy 487.9975 -43.3324) (xy 487.9975 -43.8404) (xy 487.6165 -43.8404) (xy 487.6165 -43.3324)
				)
			)
		)
	)
	(footprint ""
		(layer "B.Cu")
		(at 2.19456 -143.256 90)
		(property "Reference" "C1A11"
			(at 0 0 90)
			(layer "B.SilkS")
			(hide yes)
			(effects
				(font
					(size 1.27 1.27)
				)
				(justify mirror)
			)
		)
		(property "Value" "*"
			(at -1.1811 -2.8194 90)
			(unlocked yes)
			(layer "B.Fab")
			(hide yes)
			(effects
				(font
					(size 1.27 1.016)
					(thickness 0.1524)
				)
				(justify mirror)
			)
		)
		(property "Device Type" "SC1U10V2KX-4-GP_SMD-BCG6-SC1U1A"
			(at -1.1811 -4.3434 90)
			(unlocked yes)
			(layer "B.Fab")
			(hide yes)
			(effects
				(font
					(size 1.27 1.016)
					(thickness 0.1524)
				)
				(justify mirror)
			)
		)
		(duplicate_pad_numbers_are_jumpers no)
		(fp_rect
			(start 0.4318 0.9525)
			(end -0.4318 -0.9525)
			(stroke
				(width 0)
				(type default)
			)
			(fill no)
			(layer "B.CrtYd")
		)
		(fp_rect
			(start 0.4318 0.9525)
			(end -0.4318 -0.9525)
			(stroke
				(width 0)
				(type default)
			)
			(fill no)
			(layer "B.Fab")
		)
		(pad "1" smd custom
			(at 0 -0.4445 270)
			(size 0.1524 0.1524)
			(layers "B.Cu" "B.Mask" "B.Paste")
			(net "P5V_STBY")
			(options
				(clearance outline)
				(anchor circle)
			)
			(primitives
				(gr_poly
					(pts
						(arc
							(start 0.3048 0.2032)
							(mid 0.275042 0.275042)
							(end 0.2032 0.3048)
						)
						(arc
							(start -0.2032 0.3048)
							(mid -0.275042 0.275042)
							(end -0.3048 0.2032)
						)
						(arc
							(start -0.3048 -0.2032)
							(mid -0.275042 -0.275042)
							(end -0.2032 -0.3048)
						)
						(arc
							(start 0.2032 -0.3048)
							(mid 0.275042 -0.275042)
							(end 0.3048 -0.2032)
						)
					)
					(width 0)
					(fill yes)
				)
			)
		)
		(pad "2" smd custom
			(at 0 0.4445 270)
			(size 0.1524 0.1524)
			(layers "B.Cu" "B.Mask" "B.Paste")
			(net "GND")
			(options
				(clearance outline)
				(anchor circle)
			)
			(primitives
				(gr_poly
					(pts
						(arc
							(start 0.3048 0.2032)
							(mid 0.275042 0.275042)
							(end 0.2032 0.3048)
						)
						(arc
							(start -0.2032 0.3048)
							(mid -0.275042 0.275042)
							(end -0.3048 0.2032)
						)
						(arc
							(start -0.3048 -0.2032)
							(mid -0.275042 -0.275042)
							(end -0.2032 -0.3048)
						)
						(arc
							(start 0.2032 -0.3048)
							(mid 0.275042 -0.275042)
							(end 0.3048 -0.2032)
						)
					)
					(width 0)
					(fill yes)
				)
			)
		)
	)
	(footprint ""
		(layer "B.Cu")
		(at 269.559532 -145.0086 90)
		(property "Reference" "C5L8"
			(at -1.848866 0.752348 90)
			(unlocked yes)
			(layer "B.SilkS")
			(effects
				(font
					(size 1.27 0.9652)
					(thickness 0.1524)
				)
				(justify mirror)
			)
		)
		(property "Value" ""
			(at 0 0 90)
			(layer "B.Fab")
			(effects
				(font
					(size 1.27 1.27)
				)
				(justify mirror)
			)
		)
		(duplicate_pad_numbers_are_jumpers no)
		(fp_rect
			(start 0.500126 1.598422)
			(end -0.500126 -0.201422)
			(stroke
				(width 0)
				(type default)
			)
			(fill no)
			(layer "B.CrtYd")
		)
		(fp_line
			(start 0.500126 -0.201422)
			(end -0.500126 -0.201422)
			(stroke
				(width 0.1)
				(type default)
			)
			(layer "B.Fab")
		)
		(fp_line
			(start -0.500126 -0.201422)
			(end -0.500126 1.598422)
			(stroke
				(width 0.1)
				(type default)
			)
			(layer "B.Fab")
		)
		(fp_line
			(start 0.500126 1.598422)
			(end 0.500126 -0.201422)
			(stroke
				(width 0.1)
				(type default)
			)
			(layer "B.Fab")
		)
		(fp_line
			(start -0.500126 1.598422)
			(end 0.500126 1.598422)
			(stroke
				(width 0.1)
				(type default)
			)
			(layer "B.Fab")
		)
		(pad "1" smd rect
			(at 0 0)
			(size 0.889 0.9906)
			(layers "B.Cu" "B.Mask" "B.Paste")
			(net "PVDDQ_DEF")
		)
		(pad "2" smd rect
			(at 0 1.397)
			(size 0.889 0.9906)
			(layers "B.Cu" "B.Mask" "B.Paste")
			(net "GND")
		)
		(zone
			(layer "B.Cu")
			(hatch none 0.5)
			(connect_pads
				(clearance 0)
			)
			(min_thickness 0.25)
			(keepout
				(tracks allowed)
				(vias not_allowed)
				(pads allowed)
				(copperpour not_allowed)
				(footprints allowed)
			)
			(placement
				(enabled no)
				(sheetname "")
			)
			(fill
				(thermal_gap 0.5)
				(thermal_bridge_width 0.5)
				(island_removal_mode 0)
			)
			(polygon
				(pts
					(xy 270.512032 -145.5039) (xy 270.004032 -145.5039) (xy 270.004032 -144.5133) (xy 270.512032 -144.5133)
				)
			)
		)
		(zone
			(layer "B.Cu")
			(hatch none 0.5)
			(connect_pads
				(clearance 0)
			)
			(min_thickness 0.25)
			(keepout
				(tracks not_allowed)
				(vias allowed)
				(pads allowed)
				(copperpour not_allowed)
				(footprints allowed)
			)
			(placement
				(enabled no)
				(sheetname "")
			)
			(fill
				(thermal_gap 0.5)
				(thermal_bridge_width 0.5)
				(island_removal_mode 0)
			)
			(polygon
				(pts
					(xy 270.512032 -145.5039) (xy 270.004032 -145.5039) (xy 270.004032 -144.5133) (xy 270.512032 -144.5133)
				)
			)
		)
	)
)
